(kicad_pcb
	(version 20241229)
	(generator "pcbnew")
	(generator_version "9.0")
	(general
		(thickness 1.6296)
		(legacy_teardrops no)
	)
	(paper "A3")
	(title_block
		(title "Thunderbolt to 10GbE adapter")
		(date "2026-04-21")
		(rev "1.1.0")
		(company "Antmicro Ltd")
		(comment 1 "www.antmicro.com")
		(comment 9 "footprints 449-453 of 703")
	)
	(layers
		(0 "F.Cu" signal)
		(4 "In1.Cu" signal)
		(6 "In2.Cu" signal)
		(8 "In3.Cu" signal)
		(10 "In4.Cu" signal)
		(12 "In5.Cu" signal)
		(14 "In6.Cu" signal)
		(2 "B.Cu" signal)
		(9 "F.Adhes" user "F.Adhesive")
		(11 "B.Adhes" user "B.Adhesive")
		(13 "F.Paste" user)
		(15 "B.Paste" user)
		(5 "F.SilkS" user "F.Silkscreen")
		(7 "B.SilkS" user "B.Silkscreen")
		(1 "F.Mask" user)
		(3 "B.Mask" user)
		(17 "Dwgs.User" user "User.Drawings")
		(19 "Cmts.User" user "User.Comments")
		(21 "Eco1.User" user "User.Eco1")
		(23 "Eco2.User" user "User.Eco2")
		(25 "Edge.Cuts" user)
		(27 "Margin" user)
		(31 "F.CrtYd" user "F.Courtyard")
		(29 "B.CrtYd" user "B.Courtyard")
		(35 "F.Fab" user)
		(33 "B.Fab" user)
	)
	(footprint "antmicro-footprints:C_0402_1005Metric"
		(layer "B.Cu")
		(at 144 133.25)
		(descr "Capacitor SMD 0402")
		(tags "capacitor SMD 0402")
		(property "Reference" "C294"
			(at 2 -0.75 180)
			(layer "B.SilkS")
			(effects
				(font
					(size 0.7 0.7)
					(thickness 0.15)
				)
				(justify left bottom mirror)
			)
		)
		(property "Value" "C_1u_25V_0402"
			(at -1.022927 -2.155213 180)
			(layer "B.Fab")
			(effects
				(font
					(size 0.7 0.7)
					(thickness 0.15)
				)
				(justify left bottom mirror)
			)
		)
		(property "Datasheet" "https://www.murata.com/products/productdetail?partno=GRM155R61E105KE11%23"
			(at 0 0 180)
			(layer "B.Fab")
			(hide yes)
			(effects
				(font
					(size 1.27 1.27)
					(thickness 0.15)
				)
				(justify mirror)
			)
		)
		(property "Description" "SMD Multilayer Ceramic Capacitor, 1 µF, 25 V, 0402 [1005 Metric], ± 10%, X5R, GRM Series"
			(at 0 0 180)
			(layer "B.Fab")
			(hide yes)
			(effects
				(font
					(size 1.27 1.27)
					(thickness 0.15)
				)
				(justify mirror)
			)
		)
		(property "MPN" "GRM155R61E105KE11J"
			(at 0 0 0)
			(unlocked yes)
			(layer "B.Fab")
			(hide yes)
			(effects
				(font
					(size 1 1)
					(thickness 0.15)
				)
				(justify mirror)
			)
		)
		(property "Manufacturer" "Murata"
			(at 0 0 0)
			(unlocked yes)
			(layer "B.Fab")
			(hide yes)
			(effects
				(font
					(size 1 1)
					(thickness 0.15)
				)
				(justify mirror)
			)
		)
		(property "License" "Apache-2.0"
			(at 0 0 0)
			(unlocked yes)
			(layer "B.Fab")
			(hide yes)
			(effects
				(font
					(size 1 1)
					(thickness 0.15)
				)
				(justify mirror)
			)
		)
		(property "Author" "Antmicro"
			(at 0 0 0)
			(unlocked yes)
			(layer "B.Fab")
			(hide yes)
			(effects
				(font
					(size 1 1)
					(thickness 0.15)
				)
				(justify mirror)
			)
		)
		(property "Val" "1u"
			(at 0 0 0)
			(unlocked yes)
			(layer "B.Fab")
			(hide yes)
			(effects
				(font
					(size 1 1)
					(thickness 0.15)
				)
				(justify mirror)
			)
		)
		(property "Voltage" "25V"
			(at 0 0 0)
			(unlocked yes)
			(layer "B.Fab")
			(hide yes)
			(effects
				(font
					(size 1 1)
					(thickness 0.15)
				)
				(justify mirror)
			)
		)
		(property "Dielectric" "X5R"
			(at 0 0 0)
			(unlocked yes)
			(layer "B.Fab")
			(hide yes)
			(effects
				(font
					(size 1 1)
					(thickness 0.15)
				)
				(justify mirror)
			)
		)
		(sheetname "/2xRJ45/")
		(sheetfile "2xrj45.kicad_sch")
		(attr smd)
		(fp_rect
			(start -0.925 0.47)
			(end 0.925 -0.47)
			(stroke
				(width 0.05)
				(type default)
			)
			(fill no)
			(layer "B.CrtYd")
		)
		(fp_line
			(start -0.494 -0.248)
			(end -0.494 0.25)
			(stroke
				(width 0.15)
				(type solid)
			)
			(layer "B.Fab")
		)
		(fp_line
			(start -0.494 0.25)
			(end 0.504 0.25)
			(stroke
				(width 0.15)
				(type solid)
			)
			(layer "B.Fab")
		)
		(fp_line
			(start 0.504 -0.248)
			(end -0.494 -0.248)
			(stroke
				(width 0.15)
				(type solid)
			)
			(layer "B.Fab")
		)
		(fp_line
			(start 0.504 0.25)
			(end 0.504 -0.248)
			(stroke
				(width 0.15)
				(type solid)
			)
			(layer "B.Fab")
		)
		(fp_text user "License: Apache-2.0"
			(at -0.939 -5.799 180)
			(layer "B.Fab")
			(effects
				(font
					(size 0.7 0.7)
					(thickness 0.15)
				)
				(justify left bottom mirror)
			)
		)
		(fp_text user "${REFERENCE}"
			(at -0.939 -4.599 180)
			(layer "B.Fab")
			(effects
				(font
					(size 0.7 0.7)
					(thickness 0.15)
				)
				(justify left bottom mirror)
			)
		)
		(fp_text user "Author: Antmicro"
			(at -0.939 -3.399 180)
			(layer "B.Fab")
			(effects
				(font
					(size 0.7 0.7)
					(thickness 0.15)
				)
				(justify left bottom mirror)
			)
		)
		(pad "1" smd roundrect
			(at -0.48 0)
			(size 0.59 0.64)
			(layers "B.Cu" "B.Mask" "B.Paste")
			(roundrect_rratio 0.25)
			(net 23 "GND")
			(pintype "passive")
		)
		(pad "2" smd roundrect
			(at 0.48 0)
			(size 0.59 0.64)
			(layers "B.Cu" "B.Mask" "B.Paste")
			(roundrect_rratio 0.25)
			(net 133 "/2xRJ45/P0_CT")
			(pintype "passive")
		)
	)
	(footprint "antmicro-footprints:R_0402_1005Metric"
		(layer "B.Cu")
		(at 180.8 73)
		(descr "Resistor SMD 0402")
		(tags "resistor SMD 0402")
		(property "Reference" "R85"
			(at 3 0.4 180)
			(layer "B.SilkS")
			(effects
				(font
					(size 0.7 0.7)
					(thickness 0.15)
				)
				(justify left bottom mirror)
			)
		)
		(property "Value" "R_330R_0402"
			(at -1.011843 -1.772047 180)
			(layer "B.Fab")
			(effects
				(font
					(size 0.7 0.7)
					(thickness 0.15)
				)
				(justify left bottom mirror)
			)
		)
		(property "Datasheet" "https://www.bourns.com/docs/product-datasheets/cr.pdf"
			(at 0 0 180)
			(layer "B.Fab")
			(hide yes)
			(effects
				(font
					(size 1.27 1.27)
					(thickness 0.15)
				)
				(justify mirror)
			)
		)
		(property "Description" "SMD Chip Resistor, 330 ohm, ± 1%, 62.5 mW, 0402 [1005 Metric], Thick Film, General Purpose"
			(at 0 0 180)
			(layer "B.Fab")
			(hide yes)
			(effects
				(font
					(size 1.27 1.27)
					(thickness 0.15)
				)
				(justify mirror)
			)
		)
		(property "MPN" "CR0402-FX-3300GLF"
			(at 0 0 0)
			(unlocked yes)
			(layer "B.Fab")
			(hide yes)
			(effects
				(font
					(size 1 1)
					(thickness 0.15)
				)
				(justify mirror)
			)
		)
		(property "Manufacturer" "Bourns"
			(at 0 0 0)
			(unlocked yes)
			(layer "B.Fab")
			(hide yes)
			(effects
				(font
					(size 1 1)
					(thickness 0.15)
				)
				(justify mirror)
			)
		)
		(property "License" "Apache-2.0"
			(at 0 0 0)
			(unlocked yes)
			(layer "B.Fab")
			(hide yes)
			(effects
				(font
					(size 1 1)
					(thickness 0.15)
				)
				(justify mirror)
			)
		)
		(property "Author" "Antmicro"
			(at 0 0 0)
			(unlocked yes)
			(layer "B.Fab")
			(hide yes)
			(effects
				(font
					(size 1 1)
					(thickness 0.15)
				)
				(justify mirror)
			)
		)
		(property "Val" "330R"
			(at 0 0 0)
			(unlocked yes)
			(layer "B.Fab")
			(hide yes)
			(effects
				(font
					(size 1 1)
					(thickness 0.15)
				)
				(justify mirror)
			)
		)
		(property "Tolerance" "1%"
			(at 0 0 0)
			(unlocked yes)
			(layer "B.Fab")
			(hide yes)
			(effects
				(font
					(size 1 1)
					(thickness 0.15)
				)
				(justify mirror)
			)
		)
		(sheetname "/X710 DCDC converters/")
		(sheetfile "DCDC_converters_X710.kicad_sch")
		(attr smd)
		(fp_rect
			(start -0.925 0.47)
			(end 0.925 -0.47)
			(stroke
				(width 0.05)
				(type default)
			)
			(fill no)
			(layer "B.CrtYd")
		)
		(fp_rect
			(start -0.5 0.25)
			(end 0.5 -0.25)
			(stroke
				(width 0.15)
				(type solid)
			)
			(fill no)
			(layer "B.Fab")
		)
		(fp_text user "Author: Antmicro"
			(at -0.95 -4.169 180)
			(layer "B.Fab")
			(effects
				(font
					(size 0.7 0.7)
					(thickness 0.15)
				)
				(justify left bottom mirror)
			)
		)
		(fp_text user "${REFERENCE}"
			(at -0.95 -3.168 180)
			(layer "B.Fab")
			(effects
				(font
					(size 0.7 0.7)
					(thickness 0.15)
				)
				(justify left bottom mirror)
			)
		)
		(fp_text user "License: Apache-2.0"
			(at -0.95 -5.169 180)
			(layer "B.Fab")
			(effects
				(font
					(size 0.7 0.7)
					(thickness 0.15)
				)
				(justify left bottom mirror)
			)
		)
		(pad "1" smd roundrect
			(at -0.48 0)
			(size 0.59 0.64)
			(layers "B.Cu" "B.Mask" "B.Paste")
			(roundrect_rratio 0.25)
			(net 429 "Net-(Q3-C)")
			(pintype "passive")
		)
		(pad "2" smd roundrect
			(at 0.48 0)
			(size 0.59 0.64)
			(layers "B.Cu" "B.Mask" "B.Paste")
			(roundrect_rratio 0.25)
			(net 54 "Net-(D8-C)")
			(pintype "passive")
		)
	)
	(footprint "antmicro-footprints:R_0402_1005Metric"
		(layer "B.Cu")
		(at 140.600002 118.174998)
		(descr "Resistor SMD 0402")
		(tags "resistor SMD 0402")
		(property "Reference" "R38"
			(at 19.525001 -7.450001 180)
			(layer "B.SilkS")
			(effects
				(font
					(size 0.7 0.7)
					(thickness 0.15)
				)
				(justify mirror)
			)
		)
		(property "Value" "R_2k2_0402"
			(at -1.011843 -1.772047 180)
			(layer "B.Fab")
			(effects
				(font
					(size 0.7 0.7)
					(thickness 0.15)
				)
				(justify left bottom mirror)
			)
		)
		(property "Datasheet" "https://www.bourns.com/docs/product-datasheets/cr.pdf"
			(at 0 0 180)
			(layer "B.Fab")
			(hide yes)
			(effects
				(font
					(size 1.27 1.27)
					(thickness 0.15)
				)
				(justify mirror)
			)
		)
		(property "Description" "SMD Chip Resistor, 2.2 kohm, ± 1%, 62.5 mW, 0402 [1005 Metric], Thick Film, General Purpose"
			(at 0 0 180)
			(layer "B.Fab")
			(hide yes)
			(effects
				(font
					(size 1.27 1.27)
					(thickness 0.15)
				)
				(justify mirror)
			)
		)
		(property "MPN" "CR0402-FX-2201GLF"
			(at 0 0 0)
			(unlocked yes)
			(layer "B.Fab")
			(hide yes)
			(effects
				(font
					(size 1 1)
					(thickness 0.15)
				)
				(justify mirror)
			)
		)
		(property "Manufacturer" "Bourns"
			(at 0 0 0)
			(unlocked yes)
			(layer "B.Fab")
			(hide yes)
			(effects
				(font
					(size 1 1)
					(thickness 0.15)
				)
				(justify mirror)
			)
		)
		(property "License" "Apache-2.0"
			(at 0 0 0)
			(unlocked yes)
			(layer "B.Fab")
			(hide yes)
			(effects
				(font
					(size 1 1)
					(thickness 0.15)
				)
				(justify mirror)
			)
		)
		(property "Val" "2k2"
			(at 0 0 0)
			(unlocked yes)
			(layer "B.Fab")
			(hide yes)
			(effects
				(font
					(size 1 1)
					(thickness 0.15)
				)
				(justify mirror)
			)
		)
		(property "Tolerance" "1%"
			(at 0 0 0)
			(unlocked yes)
			(layer "B.Fab")
			(hide yes)
			(effects
				(font
					(size 1 1)
					(thickness 0.15)
				)
				(justify mirror)
			)
		)
		(property "Author" "Antmicro"
			(at 0 0 0)
			(unlocked yes)
			(layer "B.Fab")
			(hide yes)
			(effects
				(font
					(size 1 1)
					(thickness 0.15)
				)
				(justify mirror)
			)
		)
		(sheetname "/TB Controller/")
		(sheetfile "tb.kicad_sch")
		(attr smd)
		(fp_rect
			(start -0.925 0.47)
			(end 0.925 -0.47)
			(stroke
				(width 0.05)
				(type default)
			)
			(fill no)
			(layer "B.CrtYd")
		)
		(fp_rect
			(start -0.5 0.25)
			(end 0.5 -0.25)
			(stroke
				(width 0.15)
				(type solid)
			)
			(fill no)
			(layer "B.Fab")
		)
		(fp_text user "Author: Antmicro"
			(at -0.95 -4.169 180)
			(layer "B.Fab")
			(effects
				(font
					(size 0.7 0.7)
					(thickness 0.15)
				)
				(justify left bottom mirror)
			)
		)
		(fp_text user "License: Apache-2.0"
			(at -0.95 -5.169 180)
			(layer "B.Fab")
			(effects
				(font
					(size 0.7 0.7)
					(thickness 0.15)
				)
				(justify left bottom mirror)
			)
		)
		(fp_text user "${REFERENCE}"
			(at -0.95 -3.168 180)
			(layer "B.Fab")
			(effects
				(font
					(size 0.7 0.7)
					(thickness 0.15)
				)
				(justify left bottom mirror)
			)
		)
		(pad "1" smd roundrect
			(at -0.48 0)
			(size 0.59 0.64)
			(layers "B.Cu" "B.Mask" "B.Paste")
			(roundrect_rratio 0.25)
			(net 23 "GND")
			(pintype "passive")
		)
		(pad "2" smd roundrect
			(at 0.48 0)
			(size 0.59 0.64)
			(layers "B.Cu" "B.Mask" "B.Paste")
			(roundrect_rratio 0.25)
			(net 221 "Net-(U4C-DPSNK1_DDC_CLK)")
			(pintype "passive")
		)
	)
	(footprint "antmicro-footprints:C_0402_1005Metric"
		(layer "B.Cu")
		(at 134.850002 133.1 90)
		(descr "Capacitor SMD 0402")
		(tags "capacitor SMD 0402")
		(property "Reference" "C25"
			(at 8.339997 19.525001 270)
			(layer "B.SilkS")
			(effects
				(font
					(size 0.7 0.7)
					(thickness 0.15)
				)
				(justify mirror)
			)
		)
		(property "Value" "C_10u_0402"
			(at -1.022927 -2.155213 270)
			(layer "B.Fab")
			(effects
				(font
					(size 0.7 0.7)
					(thickness 0.15)
				)
				(justify left bottom mirror)
			)
		)
		(property "Datasheet" "https://www.yageo.com/en/Chart/Download/pdf/CC0402MRX5R5BB106"
			(at 0 0 270)
			(layer "B.Fab")
			(hide yes)
			(effects
				(font
					(size 1.27 1.27)
					(thickness 0.15)
				)
				(justify mirror)
			)
		)
		(property "Description" "SMD Multilayer Ceramic Capacitor, 10 µF, 6.3 V, 0402 [1005 Metric], ± 20%, X5R, CC Series"
			(at 0 0 270)
			(layer "B.Fab")
			(hide yes)
			(effects
				(font
					(size 1.27 1.27)
					(thickness 0.15)
				)
				(justify mirror)
			)
		)
		(property "MPN" "CC0402MRX5R5BB106"
			(at 0 0 90)
			(unlocked yes)
			(layer "B.Fab")
			(hide yes)
			(effects
				(font
					(size 1 1)
					(thickness 0.15)
				)
				(justify mirror)
			)
		)
		(property "Manufacturer" "YAGEO"
			(at 0 0 90)
			(unlocked yes)
			(layer "B.Fab")
			(hide yes)
			(effects
				(font
					(size 1 1)
					(thickness 0.15)
				)
				(justify mirror)
			)
		)
		(property "License" "Apache-2.0"
			(at 0 0 90)
			(unlocked yes)
			(layer "B.Fab")
			(hide yes)
			(effects
				(font
					(size 1 1)
					(thickness 0.15)
				)
				(justify mirror)
			)
		)
		(property "Val" "10u"
			(at 0 0 90)
			(unlocked yes)
			(layer "B.Fab")
			(hide yes)
			(effects
				(font
					(size 1 1)
					(thickness 0.15)
				)
				(justify mirror)
			)
		)
		(property "Voltage" ""
			(at 0 0 90)
			(unlocked yes)
			(layer "B.Fab")
			(hide yes)
			(effects
				(font
					(size 1 1)
					(thickness 0.15)
				)
				(justify mirror)
			)
		)
		(property "Dielectric" ""
			(at 0 0 90)
			(unlocked yes)
			(layer "B.Fab")
			(hide yes)
			(effects
				(font
					(size 1 1)
					(thickness 0.15)
				)
				(justify mirror)
			)
		)
		(property "Author" "Antmicro"
			(at 0 0 90)
			(unlocked yes)
			(layer "B.Fab")
			(hide yes)
			(effects
				(font
					(size 1 1)
					(thickness 0.15)
				)
				(justify mirror)
			)
		)
		(sheetname "/PD and TB DC-DC/")
		(sheetfile "PD_and_TB_DC_DC.kicad_sch")
		(attr smd)
		(fp_rect
			(start -0.925 0.47)
			(end 0.925 -0.47)
			(stroke
				(width 0.05)
				(type default)
			)
			(fill no)
			(layer "B.CrtYd")
		)
		(fp_line
			(start 0.504 -0.248)
			(end -0.494 -0.248)
			(stroke
				(width 0.15)
				(type solid)
			)
			(layer "B.Fab")
		)
		(fp_line
			(start -0.494 -0.248)
			(end -0.494 0.25)
			(stroke
				(width 0.15)
				(type solid)
			)
			(layer "B.Fab")
		)
		(fp_line
			(start 0.504 0.25)
			(end 0.504 -0.248)
			(stroke
				(width 0.15)
				(type solid)
			)
			(layer "B.Fab")
		)
		(fp_line
			(start -0.494 0.25)
			(end 0.504 0.25)
			(stroke
				(width 0.15)
				(type solid)
			)
			(layer "B.Fab")
		)
		(fp_text user "License: Apache-2.0"
			(at -0.939 -5.799 270)
			(layer "B.Fab")
			(effects
				(font
					(size 0.7 0.7)
					(thickness 0.15)
				)
				(justify left bottom mirror)
			)
		)
		(fp_text user "${REFERENCE}"
			(at -0.939 -4.599 270)
			(layer "B.Fab")
			(effects
				(font
					(size 0.7 0.7)
					(thickness 0.15)
				)
				(justify left bottom mirror)
			)
		)
		(fp_text user "Author: Antmicro"
			(at -0.939 -3.399 270)
			(layer "B.Fab")
			(effects
				(font
					(size 0.7 0.7)
					(thickness 0.15)
				)
				(justify left bottom mirror)
			)
		)
		(pad "1" smd roundrect
			(at -0.48 0 90)
			(size 0.59 0.64)
			(layers "B.Cu" "B.Mask" "B.Paste")
			(roundrect_rratio 0.25)
			(net 304 "/PD and TB DC-DC/TPS_3V3")
			(pintype "passive")
		)
		(pad "2" smd roundrect
			(at 0.48 0 90)
			(size 0.59 0.64)
			(layers "B.Cu" "B.Mask" "B.Paste")
			(roundrect_rratio 0.25)
			(net 23 "GND")
			(pintype "passive")
		)
	)
	(footprint "antmicro-footprints:C_0402_1005Metric"
		(layer "B.Cu")
		(at 130.45 123.95 -90)
		(descr "Capacitor SMD 0402")
		(tags "capacitor SMD 0402")
		(property "Reference" "C64"
			(at -7.700002 -21.900002 90)
			(layer "B.SilkS")
			(effects
				(font
					(size 0.7 0.7)
					(thickness 0.15)
				)
				(justify mirror)
			)
		)
		(property "Value" "C_1u_0402"
			(at -1.022927 -2.155213 90)
			(layer "B.Fab")
			(effects
				(font
					(size 0.7 0.7)
					(thickness 0.15)
				)
				(justify left bottom mirror)
			)
		)
		(property "Datasheet" "https://product.tdk.com/en/search/capacitor/ceramic/mlcc/info?part_no=C1005X6S1A105K050BC"
			(at 0 0 90)
			(layer "B.Fab")
			(hide yes)
			(effects
				(font
					(size 1.27 1.27)
					(thickness 0.15)
				)
				(justify mirror)
			)
		)
		(property "Description" "SMD Multilayer Ceramic Capacitor, 1 µF, 10 V, 0402 [1005 Metric], ± 10%, X6S, C"
			(at 0 0 90)
			(layer "B.Fab")
			(hide yes)
			(effects
				(font
					(size 1.27 1.27)
					(thickness 0.15)
				)
				(justify mirror)
			)
		)
		(property "MPN" "C1005X6S1A105K050BC"
			(at 0 0 270)
			(unlocked yes)
			(layer "B.Fab")
			(hide yes)
			(effects
				(font
					(size 1 1)
					(thickness 0.15)
				)
				(justify mirror)
			)
		)
		(property "Manufacturer" "TDK"
			(at 0 0 270)
			(unlocked yes)
			(layer "B.Fab")
			(hide yes)
			(effects
				(font
					(size 1 1)
					(thickness 0.15)
				)
				(justify mirror)
			)
		)
		(property "License" "Apache-2.0"
			(at 0 0 270)
			(unlocked yes)
			(layer "B.Fab")
			(hide yes)
			(effects
				(font
					(size 1 1)
					(thickness 0.15)
				)
				(justify mirror)
			)
		)
		(property "Val" "1u"
			(at 0 0 270)
			(unlocked yes)
			(layer "B.Fab")
			(hide yes)
			(effects
				(font
					(size 1 1)
					(thickness 0.15)
				)
				(justify mirror)
			)
		)
		(property "Voltage" ""
			(at 0 0 270)
			(unlocked yes)
			(layer "B.Fab")
			(hide yes)
			(effects
				(font
					(size 1 1)
					(thickness 0.15)
				)
				(justify mirror)
			)
		)
		(property "Dielectric" ""
			(at 0 0 270)
			(unlocked yes)
			(layer "B.Fab")
			(hide yes)
			(effects
				(font
					(size 1 1)
					(thickness 0.15)
				)
				(justify mirror)
			)
		)
		(property "Author" "Antmicro"
			(at 0 0 270)
			(unlocked yes)
			(layer "B.Fab")
			(hide yes)
			(effects
				(font
					(size 1 1)
					(thickness 0.15)
				)
				(justify mirror)
			)
		)
		(sheetname "/TB Controller - Power/")
		(sheetfile "tb-power.kicad_sch")
		(attr smd)
		(fp_rect
			(start -0.925 0.47)
			(end 0.925 -0.47)
			(stroke
				(width 0.05)
				(type default)
			)
			(fill no)
			(layer "B.CrtYd")
		)
		(fp_line
			(start -0.494 0.25)
			(end 0.504 0.25)
			(stroke
				(width 0.15)
				(type solid)
			)
			(layer "B.Fab")
		)
		(fp_line
			(start 0.504 0.25)
			(end 0.504 -0.248)
			(stroke
				(width 0.15)
				(type solid)
			)
			(layer "B.Fab")
		)
		(fp_line
			(start -0.494 -0.248)
			(end -0.494 0.25)
			(stroke
				(width 0.15)
				(type solid)
			)
			(layer "B.Fab")
		)
		(fp_line
			(start 0.504 -0.248)
			(end -0.494 -0.248)
			(stroke
				(width 0.15)
				(type solid)
			)
			(layer "B.Fab")
		)
		(fp_text user "${REFERENCE}"
			(at -0.939 -4.599 90)
			(layer "B.Fab")
			(effects
				(font
					(size 0.7 0.7)
					(thickness 0.15)
				)
				(justify left bottom mirror)
			)
		)
		(fp_text user "Author: Antmicro"
			(at -0.939 -3.399 90)
			(layer "B.Fab")
			(effects
				(font
					(size 0.7 0.7)
					(thickness 0.15)
				)
				(justify left bottom mirror)
			)
		)
		(fp_text user "License: Apache-2.0"
			(at -0.939 -5.799 90)
			(layer "B.Fab")
			(effects
				(font
					(size 0.7 0.7)
					(thickness 0.15)
				)
				(justify left bottom mirror)
			)
		)
		(pad "1" smd roundrect
			(at -0.48 0 270)
			(size 0.59 0.64)
			(layers "B.Cu" "B.Mask" "B.Paste")
			(roundrect_rratio 0.25)
			(net 23 "GND")
			(pintype "passive")
		)
		(pad "2" smd roundrect
			(at 0.48 0 270)
			(size 0.59 0.64)
			(layers "B.Cu" "B.Mask" "B.Paste")
			(roundrect_rratio 0.25)
			(net 402 "Net-(C52-Pad2)")
			(pintype "passive")
		)
	)
)
